FILE_TYPE = CONNECTIVITY;
{Allegro Design Entry HDL 16.6-p007 (v16-6-112F) 10/10/2012}
"PAGE_NUMBER" = 12;
0"NC";
END.
